# T6G (Grand Teton) — schematic netlist excerpt (pin names and nets, part order shuffled) for the footprints in the layout excerpt that follows; sources: Cadence DE-HDL packaged netlist, KiCad conversion of 04192023_DAF0TMB3IC0_F0TG_MB_C_brd_V02_OCP.brd

R17  Q_RES  10K 1% CHIP  pkg 0402LF  page 83 : A = RST_CPU0_PERST1_N ; B = GND
R1416  Q_RES  1K 1% CHIP  pkg 0201LF  page 342 : A = JTAG_TRST_RT_CPU1_P2_N ; B = GND
C1876  Q_CAP  0.1UF 25V 10% X7R  pkg 0402  page 143 : A = P3V3_AUX ; B = GND

(kicad_pcb
	(version 20260206)
	(generator "pcbnew")
	(generator_version "10.0")
	(general
		(thickness 1.6)
		(legacy_teardrops no)
	)
	(paper "A4")
	(title_block
		(title "04192023_DAF0TMB3IC0_F0TG_MB_C_brd_V02_OCP.brd")
		(comment 1 "Grand Teton / footprints 1049-1051 of 8354")
	)
	(layers
		(0 "F.Cu" signal "TOP")
		(4 "In1.Cu" signal "GND")
		(6 "In2.Cu" signal "IN1")
		(8 "In3.Cu" signal "GND1")
		(10 "In4.Cu" signal "IN2")
		(12 "In5.Cu" signal "GND2")
		(14 "In6.Cu" signal "IN3")
		(16 "In7.Cu" signal "GND3")
		(18 "In8.Cu" signal "VCC")
		(20 "In9.Cu" signal "VCC1")
		(22 "In10.Cu" signal "GND4")
		(24 "In11.Cu" signal "IN4")
		(26 "In12.Cu" signal "GND5")
		(28 "In13.Cu" signal "IN5")
		(30 "In14.Cu" signal "GND6")
		(32 "In15.Cu" signal "IN6")
		(34 "In16.Cu" signal "GND7")
		(2 "B.Cu" signal "BOTTOM")
		(9 "F.Adhes" user "F.Adhesive")
		(11 "B.Adhes" user "B.Adhesive")
		(13 "F.Paste" user "Package Geometry/Pastemask Top")
		(15 "B.Paste" user "Package Geometry/Pastemask Bottom")
		(5 "F.SilkS" user "Ref Des/Silkscreen Top")
		(7 "B.SilkS" user "Ref Des/Silkscreen Bottom")
		(1 "F.Mask" user "Board Geometry/Soldermask Top")
		(3 "B.Mask" user "Board Geometry/Soldermask Bottom")
		(17 "Dwgs.User" user "User.Drawings")
		(19 "Cmts.User" user "User.Comments")
		(21 "Eco1.User" user "User.Eco1")
		(23 "Eco2.User" user "User.Eco2")
		(25 "Edge.Cuts" user "Board Geometry/Outline")
		(27 "Margin" user)
		(31 "F.CrtYd" user "Package Geometry/Place Bound Top")
		(29 "B.CrtYd" user "Package Geometry/Place Bound Bottom")
		(35 "F.Fab" user "Ref Des/Assembly Top")
		(33 "B.Fab" user "Ref Des/Assembly Bottom")
	)
	(footprint ""
		(layer "F.Cu")
		(at 176.911 -133.568948 90)
		(property "Reference" "R17"
			(at 0 0 90)
			(layer "F.SilkS")
			(hide yes)
			(effects
				(font
					(size 1.27 1.27)
				)
			)
		)
		(property "Value" ""
			(at 0 0 90)
			(layer "F.Fab")
			(effects
				(font
					(size 1.27 1.27)
				)
			)
		)
		(duplicate_pad_numbers_are_jumpers no)
		(fp_line
			(start 0.7874 -0.4064)
			(end 0.7874 0.4064)
			(stroke
				(width 0.1524)
				(type default)
			)
			(layer "F.SilkS")
		)
		(fp_line
			(start -0.7874 -0.4064)
			(end 0.7874 -0.4064)
			(stroke
				(width 0.1524)
				(type default)
			)
			(layer "F.SilkS")
		)
		(fp_line
			(start 0.7874 0.4064)
			(end -0.7874 0.4064)
			(stroke
				(width 0.1524)
				(type default)
			)
			(layer "F.SilkS")
		)
		(fp_line
			(start -0.7874 0.4064)
			(end -0.7874 -0.4064)
			(stroke
				(width 0.1524)
				(type default)
			)
			(layer "F.SilkS")
		)
		(fp_line
			(start -0.12065 -0.305054)
			(end -0.12065 -0.2794)
			(stroke
				(width 0.1)
				(type default)
			)
			(layer "F.Fab")
		)
		(fp_line
			(start -0.67945 -0.305054)
			(end -0.12065 -0.305054)
			(stroke
				(width 0.1)
				(type default)
			)
			(layer "F.Fab")
		)
		(fp_line
			(start 0.67945 -0.3048)
			(end 0.67945 0.3048)
			(stroke
				(width 0.1)
				(type default)
			)
			(layer "F.Fab")
		)
		(fp_line
			(start 0.12065 -0.3048)
			(end 0.67945 -0.3048)
			(stroke
				(width 0.1)
				(type default)
			)
			(layer "F.Fab")
		)
		(fp_line
			(start 0.12065 -0.2794)
			(end 0.12065 -0.3048)
			(stroke
				(width 0.1)
				(type default)
			)
			(layer "F.Fab")
		)
		(fp_line
			(start -0.12065 -0.2794)
			(end 0.12065 -0.2794)
			(stroke
				(width 0.1)
				(type default)
			)
			(layer "F.Fab")
		)
		(fp_line
			(start 0.120396 0.2794)
			(end -0.12065 0.2794)
			(stroke
				(width 0.1)
				(type default)
			)
			(layer "F.Fab")
		)
		(fp_line
			(start -0.12065 0.2794)
			(end -0.12065 0.3048)
			(stroke
				(width 0.1)
				(type default)
			)
			(layer "F.Fab")
		)
		(fp_line
			(start 0.67945 0.3048)
			(end 0.120396 0.3048)
			(stroke
				(width 0.1)
				(type default)
			)
			(layer "F.Fab")
		)
		(fp_line
			(start 0.120396 0.3048)
			(end 0.120396 0.2794)
			(stroke
				(width 0.1)
				(type default)
			)
			(layer "F.Fab")
		)
		(fp_line
			(start -0.12065 0.3048)
			(end -0.67945 0.3048)
			(stroke
				(width 0.1)
				(type default)
			)
			(layer "F.Fab")
		)
		(fp_line
			(start -0.67945 0.3048)
			(end -0.67945 -0.305054)
			(stroke
				(width 0.1)
				(type default)
			)
			(layer "F.Fab")
		)
		(pad "1" smd circle
			(at -0.40005 0 90)
			(size 0 0)
			(layers "F.Cu" "F.Mask" "F.Paste")
			(net "RST_CPU0_PERST1_N")
		)
		(pad "2" smd circle
			(at 0.40005 0 90)
			(size 0 0)
			(layers "F.Cu" "F.Mask" "F.Paste")
			(net "GND")
		)
	)
	(footprint ""
		(layer "F.Cu")
		(at 16.20012 -76.144628 90)
		(property "Reference" "C1876"
			(at 0 0 90)
			(layer "F.SilkS")
			(hide yes)
			(effects
				(font
					(size 1.27 1.27)
				)
			)
		)
		(property "Value" ""
			(at 0 0 90)
			(layer "F.Fab")
			(effects
				(font
					(size 1.27 1.27)
				)
			)
		)
		(duplicate_pad_numbers_are_jumpers no)
		(fp_line
			(start 0.7874 -0.4064)
			(end 0.7874 0.4064)
			(stroke
				(width 0.1524)
				(type default)
			)
			(layer "F.SilkS")
		)
		(fp_line
			(start -0.7874 -0.4064)
			(end 0.7874 -0.4064)
			(stroke
				(width 0.1524)
				(type default)
			)
			(layer "F.SilkS")
		)
		(fp_line
			(start 0.7874 0.4064)
			(end -0.7874 0.4064)
			(stroke
				(width 0.1524)
				(type default)
			)
			(layer "F.SilkS")
		)
		(fp_line
			(start -0.7874 0.4064)
			(end -0.7874 -0.4064)
			(stroke
				(width 0.1524)
				(type default)
			)
			(layer "F.SilkS")
		)
		(fp_line
			(start -0.12065 -0.305054)
			(end -0.12065 -0.2794)
			(stroke
				(width 0.1)
				(type default)
			)
			(layer "F.Fab")
		)
		(fp_line
			(start -0.67945 -0.305054)
			(end -0.12065 -0.305054)
			(stroke
				(width 0.1)
				(type default)
			)
			(layer "F.Fab")
		)
		(fp_line
			(start 0.67945 -0.3048)
			(end 0.67945 0.3048)
			(stroke
				(width 0.1)
				(type default)
			)
			(layer "F.Fab")
		)
		(fp_line
			(start 0.12065 -0.3048)
			(end 0.67945 -0.3048)
			(stroke
				(width 0.1)
				(type default)
			)
			(layer "F.Fab")
		)
		(fp_line
			(start 0.12065 -0.2794)
			(end 0.12065 -0.3048)
			(stroke
				(width 0.1)
				(type default)
			)
			(layer "F.Fab")
		)
		(fp_line
			(start -0.12065 -0.2794)
			(end 0.12065 -0.2794)
			(stroke
				(width 0.1)
				(type default)
			)
			(layer "F.Fab")
		)
		(fp_line
			(start 0.120396 0.2794)
			(end -0.12065 0.2794)
			(stroke
				(width 0.1)
				(type default)
			)
			(layer "F.Fab")
		)
		(fp_line
			(start -0.12065 0.2794)
			(end -0.12065 0.3048)
			(stroke
				(width 0.1)
				(type default)
			)
			(layer "F.Fab")
		)
		(fp_line
			(start 0.67945 0.3048)
			(end 0.120396 0.3048)
			(stroke
				(width 0.1)
				(type default)
			)
			(layer "F.Fab")
		)
		(fp_line
			(start 0.120396 0.3048)
			(end 0.120396 0.2794)
			(stroke
				(width 0.1)
				(type default)
			)
			(layer "F.Fab")
		)
		(fp_line
			(start -0.12065 0.3048)
			(end -0.67945 0.3048)
			(stroke
				(width 0.1)
				(type default)
			)
			(layer "F.Fab")
		)
		(fp_line
			(start -0.67945 0.3048)
			(end -0.67945 -0.305054)
			(stroke
				(width 0.1)
				(type default)
			)
			(layer "F.Fab")
		)
		(pad "1" smd circle
			(at -0.40005 0 90)
			(size 0 0)
			(layers "F.Cu" "F.Mask" "F.Paste")
			(net "P3V3_AUX")
		)
		(pad "2" smd circle
			(at 0.40005 0 90)
			(size 0 0)
			(layers "F.Cu" "F.Mask" "F.Paste")
			(net "GND")
		)
	)
	(footprint ""
		(layer "F.Cu")
		(at 180.3908 -392.4554)
		(property "Reference" "R1416"
			(at 0 0 0)
			(layer "F.SilkS")
			(hide yes)
			(effects
				(font
					(size 1.27 1.27)
				)
			)
		)
		(property "Value" ""
			(at 0 0 0)
			(layer "F.Fab")
			(effects
				(font
					(size 1.27 1.27)
				)
			)
		)
		(duplicate_pad_numbers_are_jumpers no)
		(fp_line
			(start -0.32512 -0.175006)
			(end 0.32512 -0.175006)
			(stroke
				(width 0.1)
				(type default)
			)
			(layer "F.Fab")
		)
		(fp_line
			(start -0.32512 0.175006)
			(end -0.32512 -0.175006)
			(stroke
				(width 0.1)
				(type default)
			)
			(layer "F.Fab")
		)
		(fp_line
			(start 0.32512 -0.175006)
			(end 0.32512 0.175006)
			(stroke
				(width 0.1)
				(type default)
			)
			(layer "F.Fab")
		)
		(fp_line
			(start 0.32512 0.175006)
			(end -0.32512 0.175006)
			(stroke
				(width 0.1)
				(type default)
			)
			(layer "F.Fab")
		)
		(pad "1" smd rect
			(at -0.2667 0)
			(size 0.3048 0.381)
			(layers "F.Cu" "F.Mask" "F.Paste")
			(net "JTAG_TRST_RT_CPU1_P2_N")
		)
		(pad "2" smd rect
			(at 0.2667 0 180)
			(size 0.3048 0.381)
			(layers "F.Cu" "F.Mask" "F.Paste")
			(net "GND")
		)
	)
)
